(kicad_pcb
	(version 20260206)
	(generator "pcbnew")
	(generator_version "10.0")
	(general
		(thickness 1.6)
		(legacy_teardrops no)
	)
	(paper "A4")
	(title_block
		(title "Bryce Canyon_IOM_IOC_16318-2_OCP.brd")
		(comment 1 "Bryce Canyon / footprints 503-508 of 1605")
	)
	(layers
		(0 "F.Cu" signal "TOP")
		(4 "In1.Cu" signal "L2GND")
		(6 "In2.Cu" signal "L3")
		(8 "In3.Cu" signal "L4VCC")
		(10 "In4.Cu" signal "L5VCC")
		(12 "In5.Cu" signal "L6")
		(14 "In6.Cu" signal "L7GND")
		(2 "B.Cu" signal "BOTTOM")
		(9 "F.Adhes" user "F.Adhesive")
		(11 "B.Adhes" user "B.Adhesive")
		(13 "F.Paste" user "Package Geometry/Pastemask Top")
		(15 "B.Paste" user "Package Geometry/Pastemask Bottom")
		(5 "F.SilkS" user "Ref Des/Silkscreen Top")
		(7 "B.SilkS" user "Ref Des/Silkscreen Bottom")
		(1 "F.Mask" user "Board Geometry/Soldermask Top")
		(3 "B.Mask" user "Board Geometry/Soldermask Bottom")
		(17 "Dwgs.User" user "User.Drawings")
		(19 "Cmts.User" user "User.Comments")
		(21 "Eco1.User" user "User.Eco1")
		(23 "Eco2.User" user "User.Eco2")
		(25 "Edge.Cuts" user "Board Geometry/Outline")
		(27 "Margin" user)
		(31 "F.CrtYd" user "Package Geometry/Place Bound Top")
		(29 "B.CrtYd" user "Package Geometry/Place Bound Bottom")
		(35 "F.Fab" user "Ref Des/Assembly Top")
		(33 "B.Fab" user "Ref Des/Assembly Bottom")
	)
	(footprint ""
		(layer "F.Cu")
		(at 86.322154 -46.029118)
		(property "Reference" "R16"
			(at 0 0 0)
			(layer "F.SilkS")
			(hide yes)
			(effects
				(font
					(size 1.27 1.27)
				)
			)
		)
		(property "Value" "10KR2F-2-GP"
			(at 0.064008 -3.993896 0)
			(unlocked yes)
			(layer "F.Fab")
			(hide yes)
			(effects
				(font
					(size 1.016 1.016)
					(thickness 0.1524)
				)
			)
		)
		(property "Device Type" "R402H16"
			(at 0.064008 -5.517896 0)
			(unlocked yes)
			(layer "F.Fab")
			(hide yes)
			(effects
				(font
					(size 1.016 1.016)
					(thickness 0.1524)
				)
			)
		)
		(duplicate_pad_numbers_are_jumpers no)
		(fp_line
			(start -0.508 -0.9398)
			(end -0.508 0.9398)
			(stroke
				(width 0.1524)
				(type default)
			)
			(layer "F.SilkS")
		)
		(fp_line
			(start 0.508 -0.9398)
			(end -0.508 -0.9398)
			(stroke
				(width 0.1524)
				(type default)
			)
			(layer "F.SilkS")
		)
		(fp_rect
			(start -0.508 0.9398)
			(end 0.508 -0.9398)
			(stroke
				(width 0)
				(type default)
			)
			(fill no)
			(layer "F.CrtYd")
		)
		(fp_rect
			(start -0.508 0.9398)
			(end 0.508 -0.9398)
			(stroke
				(width 0)
				(type default)
			)
			(fill no)
			(layer "F.Fab")
		)
		(pad "1" smd custom
			(at 0 -0.4445)
			(size 0.1397 0.1397)
			(layers "F.Cu" "F.Mask" "F.Paste")
			(net "P3V3_STBY")
			(options
				(clearance outline)
				(anchor circle)
			)
			(primitives
				(gr_poly
					(pts
						(arc
							(start -0.1778 -0.2794)
							(mid -0.249642 -0.249642)
							(end -0.2794 -0.1778)
						)
						(arc
							(start -0.2794 0.1778)
							(mid -0.249642 0.249642)
							(end -0.1778 0.2794)
						)
						(arc
							(start 0.1778 0.2794)
							(mid 0.249642 0.249642)
							(end 0.2794 0.1778)
						)
						(arc
							(start 0.2794 -0.1778)
							(mid 0.249642 -0.249642)
							(end 0.1778 -0.2794)
						)
					)
					(width 0)
					(fill yes)
				)
			)
		)
		(pad "2" smd custom
			(at 0 0.4445)
			(size 0.1397 0.1397)
			(layers "F.Cu" "F.Mask" "F.Paste")
			(net "MEZZA_PRSNT1_N")
			(options
				(clearance outline)
				(anchor circle)
			)
			(primitives
				(gr_poly
					(pts
						(arc
							(start -0.1778 -0.2794)
							(mid -0.249642 -0.249642)
							(end -0.2794 -0.1778)
						)
						(arc
							(start -0.2794 0.1778)
							(mid -0.249642 0.249642)
							(end -0.1778 0.2794)
						)
						(arc
							(start 0.1778 0.2794)
							(mid 0.249642 0.249642)
							(end 0.2794 0.1778)
						)
						(arc
							(start 0.2794 -0.1778)
							(mid 0.249642 -0.249642)
							(end 0.1778 -0.2794)
						)
					)
					(width 0)
					(fill yes)
				)
			)
		)
	)
	(footprint ""
		(layer "F.Cu")
		(at 55.6768 -163.1442 180)
		(property "Reference" "R405"
			(at 0 0 180)
			(layer "F.SilkS")
			(hide yes)
			(effects
				(font
					(size 1.27 1.27)
				)
			)
		)
		(property "Value" "1KR2F-3-GP"
			(at 0.064008 -3.993896 180)
			(unlocked yes)
			(layer "F.Fab")
			(hide yes)
			(effects
				(font
					(size 1.016 1.016)
					(thickness 0.1524)
				)
			)
		)
		(property "Device Type" "R402H16"
			(at 0.064008 -5.517896 180)
			(unlocked yes)
			(layer "F.Fab")
			(hide yes)
			(effects
				(font
					(size 1.016 1.016)
					(thickness 0.1524)
				)
			)
		)
		(duplicate_pad_numbers_are_jumpers no)
		(fp_line
			(start 0.508 -0.9398)
			(end -0.508 -0.9398)
			(stroke
				(width 0.1524)
				(type default)
			)
			(layer "F.SilkS")
		)
		(fp_line
			(start -0.508 -0.9398)
			(end -0.508 0.9398)
			(stroke
				(width 0.1524)
				(type default)
			)
			(layer "F.SilkS")
		)
		(fp_rect
			(start -0.508 0.9398)
			(end 0.508 -0.9398)
			(stroke
				(width 0)
				(type default)
			)
			(fill no)
			(layer "F.CrtYd")
		)
		(fp_rect
			(start -0.508 0.9398)
			(end 0.508 -0.9398)
			(stroke
				(width 0)
				(type default)
			)
			(fill no)
			(layer "F.Fab")
		)
		(pad "1" smd custom
			(at 0 -0.4445 180)
			(size 0.1397 0.1397)
			(layers "F.Cu" "F.Mask" "F.Paste")
			(net "ADC_P1V8_STBY")
			(options
				(clearance outline)
				(anchor circle)
			)
			(primitives
				(gr_poly
					(pts
						(arc
							(start -0.1778 -0.2794)
							(mid -0.249642 -0.249642)
							(end -0.2794 -0.1778)
						)
						(arc
							(start -0.2794 0.1778)
							(mid -0.249642 0.249642)
							(end -0.1778 0.2794)
						)
						(arc
							(start 0.1778 0.2794)
							(mid 0.249642 0.249642)
							(end 0.2794 0.1778)
						)
						(arc
							(start 0.2794 -0.1778)
							(mid 0.249642 -0.249642)
							(end 0.1778 -0.2794)
						)
					)
					(width 0)
					(fill yes)
				)
			)
		)
		(pad "2" smd custom
			(at 0 0.4445 180)
			(size 0.1397 0.1397)
			(layers "F.Cu" "F.Mask" "F.Paste")
			(net "GND")
			(options
				(clearance outline)
				(anchor circle)
			)
			(primitives
				(gr_poly
					(pts
						(arc
							(start -0.1778 -0.2794)
							(mid -0.249642 -0.249642)
							(end -0.2794 -0.1778)
						)
						(arc
							(start -0.2794 0.1778)
							(mid -0.249642 0.249642)
							(end -0.1778 0.2794)
						)
						(arc
							(start 0.1778 0.2794)
							(mid 0.249642 0.249642)
							(end 0.2794 0.1778)
						)
						(arc
							(start 0.2794 -0.1778)
							(mid 0.249642 -0.249642)
							(end 0.1778 -0.2794)
						)
					)
					(width 0)
					(fill yes)
				)
			)
		)
	)
	(footprint ""
		(layer "F.Cu")
		(at 33.1216 -131.5212)
		(property "Reference" "OSC1"
			(at 0 0 0)
			(layer "F.SilkS")
			(hide yes)
			(effects
				(font
					(size 1.27 1.27)
				)
			)
		)
		(property "Value" "OSC-24MHZ-18-GP"
			(at 0.0127 -2.7686 0)
			(unlocked yes)
			(layer "F.Fab")
			(hide yes)
			(effects
				(font
					(size 1.016 1.016)
					(thickness 0.1524)
				)
			)
		)
		(property "Device Type" "OSC-3225-4P-3H48"
			(at 0.0127 -4.2926 0)
			(unlocked yes)
			(layer "F.Fab")
			(hide yes)
			(effects
				(font
					(size 1.016 1.016)
					(thickness 0.1524)
				)
			)
		)
		(duplicate_pad_numbers_are_jumpers no)
		(fp_line
			(start -2.2352 1.6256)
			(end -2.2352 0.635)
			(stroke
				(width 0.3302)
				(type default)
			)
			(layer "F.SilkS")
		)
		(fp_line
			(start -2.1209 -1.5367)
			(end 2.1209 -1.5367)
			(stroke
				(width 0.1524)
				(type default)
			)
			(layer "F.SilkS")
		)
		(fp_line
			(start -2.1209 1.5367)
			(end -2.1209 -1.5367)
			(stroke
				(width 0.1524)
				(type default)
			)
			(layer "F.SilkS")
		)
		(fp_line
			(start -1.3208 1.6256)
			(end -2.2352 1.6256)
			(stroke
				(width 0.3302)
				(type default)
			)
			(layer "F.SilkS")
		)
		(fp_line
			(start 2.1209 -1.5367)
			(end 2.1209 1.5367)
			(stroke
				(width 0.1524)
				(type default)
			)
			(layer "F.SilkS")
		)
		(fp_line
			(start 2.1209 1.5367)
			(end -2.1209 1.5367)
			(stroke
				(width 0.1524)
				(type default)
			)
			(layer "F.SilkS")
		)
		(fp_poly
			(pts
				(xy -2.8321 1.459992) (xy -2.8321 0.189992) (xy -2.1971 0.824992)
			)
			(stroke
				(width 0)
				(type default)
			)
			(fill yes)
			(layer "F.SilkS")
		)
		(fp_rect
			(start -1.6002 1.2446)
			(end 1.6002 -1.2446)
			(stroke
				(width 0)
				(type default)
			)
			(fill no)
			(layer "F.CrtYd")
		)
		(fp_poly
			(pts
				(xy -2.3749 1.7907) (xy -2.3749 -1.7907) (xy 2.3749 -1.7907) (xy 2.3749 1.7907) (xy 1.6002 1.7907)
				(xy 1.6002 -1.2446) (xy -1.6002 -1.2446) (xy -1.6002 1.2446) (xy 1.59512 1.2446) (xy 1.59512 1.7907)
			)
			(stroke
				(width 0)
				(type default)
			)
			(fill no)
			(layer "F.CrtYd")
		)
		(fp_rect
			(start -2.3749 1.7907)
			(end 2.3749 -1.7907)
			(stroke
				(width 0)
				(type default)
			)
			(fill no)
			(layer "F.Fab")
		)
		(pad "1" smd rect
			(at -1.171448 0.824992)
			(size 1.397 0.9144)
			(layers "F.Cu" "F.Mask" "F.Paste")
			(net "OSC_OE")
		)
		(pad "2" smd rect
			(at 1.171448 0.824992)
			(size 1.397 0.9144)
			(layers "F.Cu" "F.Mask" "F.Paste")
			(net "GND")
		)
		(pad "3" smd rect
			(at 1.171448 -0.824992)
			(size 1.397 0.9144)
			(layers "F.Cu" "F.Mask" "F.Paste")
			(net "OSC_OUT")
		)
		(pad "4" smd rect
			(at -1.171448 -0.824992)
			(size 1.397 0.9144)
			(layers "F.Cu" "F.Mask" "F.Paste")
			(net "P3V3_STBY")
		)
		(zone
			(layer "F.Cu")
			(hatch none 0.5)
			(connect_pads
				(clearance 0)
			)
			(min_thickness 0.25)
			(keepout
				(tracks not_allowed)
				(vias allowed)
				(pads allowed)
				(copperpour not_allowed)
				(footprints allowed)
			)
			(placement
				(enabled no)
				(sheetname "")
			)
			(fill
				(thermal_gap 0.5)
				(thermal_bridge_width 0.5)
				(island_removal_mode 0)
			)
			(polygon
				(pts
					(xy 32.973772 -131.478528) (xy 33.269428 -131.478528) (xy 33.269428 -131.563872) (xy 32.973772 -131.563872)
				)
			)
		)
		(zone
			(layer "F.Cu")
			(hatch none 0.5)
			(connect_pads
				(clearance 0)
			)
			(min_thickness 0.25)
			(keepout
				(tracks allowed)
				(vias not_allowed)
				(pads allowed)
				(copperpour not_allowed)
				(footprints allowed)
			)
			(placement
				(enabled no)
				(sheetname "")
			)
			(fill
				(thermal_gap 0.5)
				(thermal_bridge_width 0.5)
				(island_removal_mode 0)
			)
			(polygon
				(pts
					(xy 32.648652 -130.239008) (xy 32.648652 -131.153408) (xy 31.251652 -131.153408) (xy 31.251652 -131.888992)
					(xy 32.648652 -131.888992) (xy 32.648652 -132.803392) (xy 33.594548 -132.803392) (xy 33.594548 -131.888992)
					(xy 34.991548 -131.888992) (xy 34.991548 -131.153408) (xy 33.594548 -131.153408) (xy 33.594548 -130.239008)
				)
			)
		)
	)
	(footprint ""
		(layer "F.Cu")
		(at 187.198 -48.4378 180)
		(property "Reference" "R665"
			(at 0 0 180)
			(layer "F.SilkS")
			(hide yes)
			(effects
				(font
					(size 1.27 1.27)
				)
			)
		)
		(property "Value" "10KR2F-2-GP"
			(at 0.064008 -3.993896 180)
			(unlocked yes)
			(layer "F.Fab")
			(hide yes)
			(effects
				(font
					(size 1.016 1.016)
					(thickness 0.1524)
				)
			)
		)
		(property "Device Type" "R402H16"
			(at 0.064008 -5.517896 180)
			(unlocked yes)
			(layer "F.Fab")
			(hide yes)
			(effects
				(font
					(size 1.016 1.016)
					(thickness 0.1524)
				)
			)
		)
		(duplicate_pad_numbers_are_jumpers no)
		(fp_line
			(start 0.508 -0.9398)
			(end -0.508 -0.9398)
			(stroke
				(width 0.1524)
				(type default)
			)
			(layer "F.SilkS")
		)
		(fp_line
			(start -0.508 -0.9398)
			(end -0.508 0.9398)
			(stroke
				(width 0.1524)
				(type default)
			)
			(layer "F.SilkS")
		)
		(fp_rect
			(start -0.508 0.9398)
			(end 0.508 -0.9398)
			(stroke
				(width 0)
				(type default)
			)
			(fill no)
			(layer "F.CrtYd")
		)
		(fp_rect
			(start -0.508 0.9398)
			(end 0.508 -0.9398)
			(stroke
				(width 0)
				(type default)
			)
			(fill no)
			(layer "F.Fab")
		)
		(pad "1" smd custom
			(at 0 -0.4445 180)
			(size 0.1397 0.1397)
			(layers "F.Cu" "F.Mask" "F.Paste")
			(net "P1V8")
			(options
				(clearance outline)
				(anchor circle)
			)
			(primitives
				(gr_poly
					(pts
						(arc
							(start -0.1778 -0.2794)
							(mid -0.249642 -0.249642)
							(end -0.2794 -0.1778)
						)
						(arc
							(start -0.2794 0.1778)
							(mid -0.249642 0.249642)
							(end -0.1778 0.2794)
						)
						(arc
							(start 0.1778 0.2794)
							(mid 0.249642 0.249642)
							(end 0.2794 0.1778)
						)
						(arc
							(start 0.2794 -0.1778)
							(mid 0.249642 -0.249642)
							(end 0.1778 -0.2794)
						)
					)
					(width 0)
					(fill yes)
				)
			)
		)
		(pad "2" smd custom
			(at 0 0.4445 180)
			(size 0.1397 0.1397)
			(layers "F.Cu" "F.Mask" "F.Paste")
			(net "XM_CS0_N")
			(options
				(clearance outline)
				(anchor circle)
			)
			(primitives
				(gr_poly
					(pts
						(arc
							(start -0.1778 -0.2794)
							(mid -0.249642 -0.249642)
							(end -0.2794 -0.1778)
						)
						(arc
							(start -0.2794 0.1778)
							(mid -0.249642 0.249642)
							(end -0.1778 0.2794)
						)
						(arc
							(start 0.1778 0.2794)
							(mid 0.249642 0.249642)
							(end 0.2794 0.1778)
						)
						(arc
							(start 0.2794 -0.1778)
							(mid 0.249642 -0.249642)
							(end 0.1778 -0.2794)
						)
					)
					(width 0)
					(fill yes)
				)
			)
		)
	)
	(footprint ""
		(layer "F.Cu")
		(at 93.875606 -129.506726 -90)
		(property "Reference" "U33"
			(at 0 0 270)
			(layer "F.SilkS")
			(hide yes)
			(effects
				(font
					(size 1.27 1.27)
				)
			)
		)
		(property "Value" "TS5A23157DGSR-GP"
			(at 0 -11.1252 270)
			(unlocked yes)
			(layer "F.Fab")
			(hide yes)
			(effects
				(font
					(size 1.016 1.016)
					(thickness 0.1524)
				)
			)
		)
		(property "Device Type" "MSOP10H44"
			(at 0 -12.6492 270)
			(unlocked yes)
			(layer "F.Fab")
			(hide yes)
			(effects
				(font
					(size 1.016 1.016)
					(thickness 0.1524)
				)
			)
		)
		(duplicate_pad_numbers_are_jumpers no)
		(fp_line
			(start -2.0066 1.016)
			(end -2.0066 -1.016)
			(stroke
				(width 0.1524)
				(type default)
			)
			(layer "F.SilkS")
		)
		(fp_line
			(start -1.8288 1.016)
			(end -1.8288 3.048)
			(stroke
				(width 0.508)
				(type default)
			)
			(layer "F.SilkS")
		)
		(fp_line
			(start 1.143 1.016)
			(end -2.0066 1.016)
			(stroke
				(width 0.1524)
				(type default)
			)
			(layer "F.SilkS")
		)
		(fp_line
			(start -1.5748 0)
			(end -1.9558 0.381)
			(stroke
				(width 0.1524)
				(type default)
			)
			(layer "F.SilkS")
		)
		(fp_line
			(start -1.5748 0)
			(end -1.9558 -0.381)
			(stroke
				(width 0.1524)
				(type default)
			)
			(layer "F.SilkS")
		)
		(fp_line
			(start -2.0066 -1.016)
			(end 1.143 -1.016)
			(stroke
				(width 0.1524)
				(type default)
			)
			(layer "F.SilkS")
		)
		(fp_line
			(start 1.143 -1.016)
			(end 1.143 1.016)
			(stroke
				(width 0.1524)
				(type default)
			)
			(layer "F.SilkS")
		)
		(fp_poly
			(pts
				(xy -2.0828 3.3401) (xy 2.0828 3.3401) (xy 2.0828 -3.3401) (xy -2.0828 -3.3401)
			)
			(stroke
				(width 0)
				(type default)
			)
			(fill no)
			(layer "F.CrtYd")
		)
		(fp_poly
			(pts
				(xy -2.0828 3.3401) (xy 2.0828 3.3401) (xy 2.0828 -3.3401) (xy -2.0828 -3.3401)
			)
			(stroke
				(width 0)
				(type default)
			)
			(fill no)
			(layer "F.Fab")
		)
		(pad "1" smd rect
			(at -0.99949 2.0701 270)
			(size 0.3048 1.524)
			(layers "F.Cu" "F.Mask" "F.Paste")
			(net "UART_SEL_MUX")
		)
		(pad "2" smd rect
			(at -0.50038 2.0701 270)
			(size 0.3048 1.524)
			(layers "F.Cu" "F.Mask" "F.Paste")
			(net "UART_BMC_TX")
		)
		(pad "3" smd rect
			(at 0 2.0701 270)
			(size 0.3048 1.524)
			(layers "F.Cu" "F.Mask" "F.Paste")
			(net "GND")
		)
		(pad "4" smd rect
			(at 0.50038 2.0701 270)
			(size 0.3048 1.524)
			(layers "F.Cu" "F.Mask" "F.Paste")
			(net "UART_BMC_RX")
		)
		(pad "5" smd rect
			(at 0.99949 2.0701 270)
			(size 0.3048 1.524)
			(layers "F.Cu" "F.Mask" "F.Paste")
			(net "UART_SEL_MUX")
		)
		(pad "6" smd rect
			(at 0.99949 -2.0701 270)
			(size 0.3048 1.524)
			(layers "F.Cu" "F.Mask" "F.Paste")
			(net "DEBUG_UART_IOM_RX")
		)
		(pad "7" smd rect
			(at 0.50038 -2.0701 270)
			(size 0.3048 1.524)
			(layers "F.Cu" "F.Mask" "F.Paste")
			(net "UART_COMP_IN_RX")
		)
		(pad "8" smd rect
			(at 0 -2.0701 270)
			(size 0.3048 1.524)
			(layers "F.Cu" "F.Mask" "F.Paste")
			(net "P3V3_STBY")
		)
		(pad "9" smd rect
			(at -0.50038 -2.0701 270)
			(size 0.3048 1.524)
			(layers "F.Cu" "F.Mask" "F.Paste")
			(net "UART_COMP_OUT_TX")
		)
		(pad "10" smd rect
			(at -0.99949 -2.0701 270)
			(size 0.3048 1.524)
			(layers "F.Cu" "F.Mask" "F.Paste")
			(net "DEBUG_UART_IOM_TX")
		)
	)
	(footprint ""
		(layer "F.Cu")
		(at 171.494196 -117.368066)
		(property "Reference" "C219"
			(at 0 0 0)
			(layer "F.SilkS")
			(hide yes)
			(effects
				(font
					(size 1.27 1.27)
				)
			)
		)
		(property "Value" "SCD47U25V3KX-3-GP"
			(at 0 -2.8194 0)
			(unlocked yes)
			(layer "F.Fab")
			(hide yes)
			(effects
				(font
					(size 1.016 1.016)
					(thickness 0.1524)
				)
			)
		)
		(property "Device Type" "C603H36"
			(at 0 -4.3434 0)
			(unlocked yes)
			(layer "F.Fab")
			(hide yes)
			(effects
				(font
					(size 1.016 1.016)
					(thickness 0.1524)
				)
			)
		)
		(duplicate_pad_numbers_are_jumpers no)
		(fp_line
			(start 0.508 0)
			(end -0.508 0)
			(stroke
				(width 0.2032)
				(type default)
			)
			(layer "F.SilkS")
		)
		(fp_rect
			(start -0.5842 1.3335)
			(end 0.5842 -1.3335)
			(stroke
				(width 0)
				(type default)
			)
			(fill no)
			(layer "F.CrtYd")
		)
		(fp_rect
			(start -0.5842 1.3335)
			(end 0.5842 -1.3335)
			(stroke
				(width 0)
				(type default)
			)
			(fill no)
			(layer "F.Fab")
		)
		(pad "1" smd custom
			(at 0 -0.762)
			(size 0.2159 0.2159)
			(layers "F.Cu" "F.Mask" "F.Paste")
			(net "PQ4_D")
			(options
				(clearance outline)
				(anchor circle)
			)
			(primitives
				(gr_poly
					(pts
						(arc
							(start -0.3302 -0.4318)
							(mid -0.402042 -0.402042)
							(end -0.4318 -0.3302)
						)
						(arc
							(start -0.4318 0.3302)
							(mid -0.402042 0.402042)
							(end -0.3302 0.4318)
						)
						(arc
							(start 0.3302 0.4318)
							(mid 0.402042 0.402042)
							(end 0.4318 0.3302)
						)
						(arc
							(start 0.4318 -0.3302)
							(mid 0.402042 -0.402042)
							(end 0.3302 -0.4318)
						)
					)
					(width 0)
					(fill yes)
				)
			)
		)
		(pad "2" smd custom
			(at 0 0.762)
			(size 0.2159 0.2159)
			(layers "F.Cu" "F.Mask" "F.Paste")
			(net "P1V8")
			(options
				(clearance outline)
				(anchor circle)
			)
			(primitives
				(gr_poly
					(pts
						(arc
							(start -0.3302 -0.4318)
							(mid -0.402042 -0.402042)
							(end -0.4318 -0.3302)
						)
						(arc
							(start -0.4318 0.3302)
							(mid -0.402042 0.402042)
							(end -0.3302 0.4318)
						)
						(arc
							(start 0.3302 0.4318)
							(mid 0.402042 0.402042)
							(end 0.4318 0.3302)
						)
						(arc
							(start 0.4318 -0.3302)
							(mid 0.402042 -0.402042)
							(end 0.3302 -0.4318)
						)
					)
					(width 0)
					(fill yes)
				)
			)
		)
	)
)
